(kicad_pcb
	(version 20241229)
	(generator "pcbnew")
	(generator_version "9.0")
	(general
		(thickness 1.61)
		(legacy_teardrops no)
	)
	(paper "A3")
	(title_block
		(title "SO-DIMM DDR5 Tester")
		(date "2025-11-26")
		(rev "1.3.0")
		(comment 9 "footprints 164-169 of 627")
	)
	(layers
		(0 "F.Cu" signal)
		(4 "In1.Cu" power)
		(6 "In2.Cu" mixed)
		(8 "In3.Cu" power)
		(10 "In4.Cu" mixed)
		(12 "In5.Cu" power)
		(14 "In6.Cu" mixed)
		(16 "In7.Cu" power)
		(18 "In8.Cu" power)
		(20 "In9.Cu" mixed)
		(22 "In10.Cu" power)
		(2 "B.Cu" signal)
		(9 "F.Adhes" user "F.Adhesive")
		(11 "B.Adhes" user "B.Adhesive")
		(13 "F.Paste" user)
		(15 "B.Paste" user)
		(5 "F.SilkS" user "F.Silkscreen")
		(7 "B.SilkS" user "B.Silkscreen")
		(1 "F.Mask" user)
		(3 "B.Mask" user)
		(17 "Dwgs.User" user "User.Drawings")
		(19 "Cmts.User" user "User.Comments")
		(21 "Eco1.User" user "User.Eco1")
		(23 "Eco2.User" user "User.Eco2")
		(25 "Edge.Cuts" user)
		(27 "Margin" user)
		(31 "F.CrtYd" user "F.Courtyard")
		(29 "B.CrtYd" user "B.Courtyard")
		(35 "F.Fab" user)
		(33 "B.Fab" user)
	)
	(footprint "antmicro-footprints:R_0402_1005Metric"
		(layer "F.Cu")
		(at 107.3 184.8 -90)
		(descr "Resistor SMD 0402")
		(tags "resistor SMD 0402")
		(property "Reference" "R94"
			(at -1.122484 -0.772697 270)
			(layer "F.SilkS")
			(hide yes)
			(effects
				(font
					(size 0.7 0.7)
					(thickness 0.15)
				)
				(justify left bottom)
			)
		)
		(property "Value" "R_4k7_0402"
			(at -1.011843 1.772047 270)
			(layer "F.Fab")
			(effects
				(font
					(size 0.7 0.7)
					(thickness 0.15)
				)
				(justify left bottom)
			)
		)
		(property "Datasheet" "https://www.bourns.com/docs/product-datasheets/cr.pdf"
			(at 0 0 270)
			(layer "F.Fab")
			(hide yes)
			(effects
				(font
					(size 1.27 1.27)
					(thickness 0.15)
				)
			)
		)
		(property "Author" "Antmicro"
			(at -77.5 292.1 0)
			(layer "F.Fab")
			(hide yes)
			(effects
				(font
					(size 1 1)
					(thickness 0.15)
				)
			)
		)
		(property "License" "Apache-2.0"
			(at -77.5 292.1 0)
			(layer "F.Fab")
			(hide yes)
			(effects
				(font
					(size 1 1)
					(thickness 0.15)
				)
			)
		)
		(property "MPN" "CR0402-FX-4701GLF"
			(at -77.5 292.1 0)
			(layer "F.Fab")
			(hide yes)
			(effects
				(font
					(size 1 1)
					(thickness 0.15)
				)
			)
		)
		(property "Manufacturer" "Bourns"
			(at -77.5 292.1 0)
			(layer "F.Fab")
			(hide yes)
			(effects
				(font
					(size 1 1)
					(thickness 0.15)
				)
			)
		)
		(property "Tolerance" "1%"
			(at -77.5 292.1 0)
			(layer "F.Fab")
			(hide yes)
			(effects
				(font
					(size 1 1)
					(thickness 0.15)
				)
			)
		)
		(property "Val" "4k7"
			(at -77.5 292.1 0)
			(layer "F.Fab")
			(hide yes)
			(effects
				(font
					(size 1 1)
					(thickness 0.15)
				)
			)
		)
		(sheetname "/Debug FTDI/")
		(sheetfile "debug-ftdi.kicad_sch")
		(attr smd)
		(fp_rect
			(start -0.93 -0.47)
			(end 0.93 0.47)
			(stroke
				(width 0.05)
				(type solid)
			)
			(fill no)
			(layer "F.CrtYd")
		)
		(fp_rect
			(start -0.5 -0.25)
			(end 0.5 0.25)
			(stroke
				(width 0.15)
				(type solid)
			)
			(fill no)
			(layer "F.Fab")
		)
		(pad "1" smd roundrect
			(at -0.485 0 270)
			(size 0.59 0.64)
			(layers "F.Cu" "F.Mask" "F.Paste")
			(roundrect_rratio 0.25)
			(net 41 "+3V3_AON")
			(pintype "passive")
		)
		(pad "2" smd roundrect
			(at 0.485 0 270)
			(size 0.59 0.64)
			(layers "F.Cu" "F.Mask" "F.Paste")
			(roundrect_rratio 0.25)
			(net 671 "/Debug FTDI/FTDI.SCL")
			(pintype "passive")
		)
	)
	(footprint "antmicro-footprints:R_0402_1005Metric"
		(layer "F.Cu")
		(at 91.748501 126.719 -90)
		(descr "Resistor SMD 0402")
		(tags "resistor SMD 0402")
		(property "Reference" "R13"
			(at -1.122484 -0.772697 270)
			(layer "F.SilkS")
			(hide yes)
			(effects
				(font
					(size 0.7 0.7)
					(thickness 0.15)
				)
				(justify left bottom)
			)
		)
		(property "Value" "R_330R_0402"
			(at -1.011843 1.772047 270)
			(layer "F.Fab")
			(effects
				(font
					(size 0.7 0.7)
					(thickness 0.15)
				)
				(justify left bottom)
			)
		)
		(property "Datasheet" "https://www.bourns.com/docs/product-datasheets/cr.pdf"
			(at 0 0 270)
			(layer "F.Fab")
			(hide yes)
			(effects
				(font
					(size 1.27 1.27)
					(thickness 0.15)
				)
			)
		)
		(property "Author" "Antmicro"
			(at -34.970499 218.467501 0)
			(layer "F.Fab")
			(hide yes)
			(effects
				(font
					(size 1 1)
					(thickness 0.15)
				)
			)
		)
		(property "License" "Apache-2.0"
			(at -34.970499 218.467501 0)
			(layer "F.Fab")
			(hide yes)
			(effects
				(font
					(size 1 1)
					(thickness 0.15)
				)
			)
		)
		(property "MPN" "CR0402-FX-3300GLF"
			(at -34.970499 218.467501 0)
			(layer "F.Fab")
			(hide yes)
			(effects
				(font
					(size 1 1)
					(thickness 0.15)
				)
			)
		)
		(property "Manufacturer" "Bourns"
			(at -34.970499 218.467501 0)
			(layer "F.Fab")
			(hide yes)
			(effects
				(font
					(size 1 1)
					(thickness 0.15)
				)
			)
		)
		(property "Tolerance" "1%"
			(at -34.970499 218.467501 0)
			(layer "F.Fab")
			(hide yes)
			(effects
				(font
					(size 1 1)
					(thickness 0.15)
				)
			)
		)
		(property "Val" "330R"
			(at -34.970499 218.467501 0)
			(layer "F.Fab")
			(hide yes)
			(effects
				(font
					(size 1 1)
					(thickness 0.15)
				)
			)
		)
		(sheetname "/FPGA Config/")
		(sheetfile "fpga-config.kicad_sch")
		(attr smd)
		(fp_rect
			(start -0.93 -0.47)
			(end 0.93 0.47)
			(stroke
				(width 0.05)
				(type solid)
			)
			(fill no)
			(layer "F.CrtYd")
		)
		(fp_rect
			(start -0.5 -0.25)
			(end 0.5 0.25)
			(stroke
				(width 0.15)
				(type solid)
			)
			(fill no)
			(layer "F.Fab")
		)
		(pad "1" smd roundrect
			(at -0.485 0 270)
			(size 0.59 0.64)
			(layers "F.Cu" "F.Mask" "F.Paste")
			(roundrect_rratio 0.25)
			(net 306 "Net-(D3-Pad2)")
			(pintype "passive")
		)
		(pad "2" smd roundrect
			(at 0.485 0 270)
			(size 0.59 0.64)
			(layers "F.Cu" "F.Mask" "F.Paste")
			(roundrect_rratio 0.25)
			(net 352 "Net-(Q3-D)")
			(pintype "passive")
		)
	)
	(footprint "antmicro-footprints:C_0402_1005Metric"
		(layer "F.Cu")
		(at 82.9995 182.9 90)
		(descr "Capacitor SMD 0402")
		(tags "capacitor SMD 0402")
		(property "Reference" "C132"
			(at 0 -0.699 90)
			(layer "F.SilkS")
			(hide yes)
			(effects
				(font
					(size 0.7 0.7)
					(thickness 0.15)
				)
				(justify left bottom)
			)
		)
		(property "Value" "C_100n_0402"
			(at -1.022927 2.155213 90)
			(layer "F.Fab")
			(effects
				(font
					(size 0.7 0.7)
					(thickness 0.15)
				)
				(justify left bottom)
			)
		)
		(property "Datasheet" "https://www.murata.com/products/productdetail?partno=GRM155R61H104KE14%23"
			(at 0 0 90)
			(layer "F.Fab")
			(hide yes)
			(effects
				(font
					(size 1.27 1.27)
					(thickness 0.15)
				)
			)
		)
		(property "Author" "Antmicro"
			(at 265.8995 99.9005 0)
			(layer "F.Fab")
			(hide yes)
			(effects
				(font
					(size 1 1)
					(thickness 0.15)
				)
			)
		)
		(property "Dielectric" "X5R"
			(at 265.8995 99.9005 0)
			(layer "F.Fab")
			(hide yes)
			(effects
				(font
					(size 1 1)
					(thickness 0.15)
				)
			)
		)
		(property "License" "Apache-2.0"
			(at 265.8995 99.9005 0)
			(layer "F.Fab")
			(hide yes)
			(effects
				(font
					(size 1 1)
					(thickness 0.15)
				)
			)
		)
		(property "MPN" "GRM155R61H104KE14D"
			(at 265.8995 99.9005 0)
			(layer "F.Fab")
			(hide yes)
			(effects
				(font
					(size 1 1)
					(thickness 0.15)
				)
			)
		)
		(property "Manufacturer" "Murata"
			(at 265.8995 99.9005 0)
			(layer "F.Fab")
			(hide yes)
			(effects
				(font
					(size 1 1)
					(thickness 0.15)
				)
			)
		)
		(property "Val" "100n"
			(at 265.8995 99.9005 0)
			(layer "F.Fab")
			(hide yes)
			(effects
				(font
					(size 1 1)
					(thickness 0.15)
				)
			)
		)
		(property "Voltage" "50V"
			(at 265.8995 99.9005 0)
			(layer "F.Fab")
			(hide yes)
			(effects
				(font
					(size 1 1)
					(thickness 0.15)
				)
			)
		)
		(sheetname "/HDMI + SD Card/")
		(sheetfile "hdmi-sd-card.kicad_sch")
		(attr smd)
		(fp_rect
			(start -0.9659 -0.481258)
			(end 0.9649 0.458742)
			(stroke
				(width 0.05)
				(type solid)
			)
			(fill no)
			(layer "F.CrtYd")
		)
		(fp_line
			(start 0.499 -0.25)
			(end 0.499 0.248)
			(stroke
				(width 0.15)
				(type solid)
			)
			(layer "F.Fab")
		)
		(fp_line
			(start -0.499 -0.25)
			(end 0.499 -0.25)
			(stroke
				(width 0.15)
				(type solid)
			)
			(layer "F.Fab")
		)
		(fp_line
			(start 0.499 0.248)
			(end -0.499 0.248)
			(stroke
				(width 0.15)
				(type solid)
			)
			(layer "F.Fab")
		)
		(fp_line
			(start -0.499 0.248)
			(end -0.499 -0.25)
			(stroke
				(width 0.15)
				(type solid)
			)
			(layer "F.Fab")
		)
		(pad "1" smd roundrect
			(at -0.484 0 90)
			(size 0.59 0.64)
			(layers "F.Cu" "F.Mask" "F.Paste")
			(roundrect_rratio 0.25)
			(net 251 "Net-(C132-Pad1)")
			(pintype "passive")
		)
		(pad "2" smd roundrect
			(at 0.484 0 90)
			(size 0.59 0.64)
			(layers "F.Cu" "F.Mask" "F.Paste")
			(roundrect_rratio 0.25)
			(net 1 "GND")
			(pintype "passive")
		)
	)
	(footprint "antmicro-footprints:C_0603_1608Metric"
		(layer "F.Cu")
		(at 193.713499 134.94 -90)
		(descr "Capacitor SMD 0603")
		(tags "capacitor 0603")
		(property "Reference" "C181"
			(at -1.42757 -1.000252 270)
			(layer "F.SilkS")
			(hide yes)
			(effects
				(font
					(size 0.7 0.7)
					(thickness 0.15)
				)
				(justify left bottom)
			)
		)
		(property "Value" "C_1u_25V_0603"
			(at -1.42757 1.770288 270)
			(layer "F.Fab")
			(effects
				(font
					(size 0.7 0.7)
					(thickness 0.15)
				)
				(justify left bottom)
			)
		)
		(property "Datasheet" "https://product.samsungsem.com/mlcc/CL10A105KA8NNN.do"
			(at 0 0 270)
			(layer "F.Fab")
			(hide yes)
			(effects
				(font
					(size 1.27 1.27)
					(thickness 0.15)
				)
			)
		)
		(property "Author" "Antmicro"
			(at 58.773499 328.653499 0)
			(layer "F.Fab")
			(hide yes)
			(effects
				(font
					(size 1 1)
					(thickness 0.15)
				)
			)
		)
		(property "Dielectric" ""
			(at 58.773499 328.653499 0)
			(layer "F.Fab")
			(hide yes)
			(effects
				(font
					(size 1 1)
					(thickness 0.15)
				)
			)
		)
		(property "License" "Apache-2.0"
			(at 58.773499 328.653499 0)
			(layer "F.Fab")
			(hide yes)
			(effects
				(font
					(size 1 1)
					(thickness 0.15)
				)
			)
		)
		(property "MPN" "CL10A105KA8NNNC"
			(at 58.773499 328.653499 0)
			(layer "F.Fab")
			(hide yes)
			(effects
				(font
					(size 1 1)
					(thickness 0.15)
				)
			)
		)
		(property "Manufacturer" "Samsung Electro-Mechanics"
			(at 58.773499 328.653499 0)
			(layer "F.Fab")
			(hide yes)
			(effects
				(font
					(size 1 1)
					(thickness 0.15)
				)
			)
		)
		(property "Val" "1u/25V"
			(at 58.773499 328.653499 0)
			(layer "F.Fab")
			(hide yes)
			(effects
				(font
					(size 1 1)
					(thickness 0.15)
				)
			)
		)
		(property "Voltage" ""
			(at 58.773499 328.653499 0)
			(layer "F.Fab")
			(hide yes)
			(effects
				(font
					(size 1 1)
					(thickness 0.15)
				)
			)
		)
		(sheetname "/Supply/")
		(sheetfile "supply.kicad_sch")
		(attr smd)
		(fp_line
			(start -0.3 0.3)
			(end 0.3 0.3)
			(stroke
				(width 0.15)
				(type solid)
			)
			(layer "F.SilkS")
		)
		(fp_line
			(start -0.3 -0.3)
			(end 0.3 -0.3)
			(stroke
				(width 0.15)
				(type solid)
			)
			(layer "F.SilkS")
		)
		(fp_rect
			(start -1.24 -0.7)
			(end 1.24 0.7)
			(stroke
				(width 0.05)
				(type solid)
			)
			(fill no)
			(layer "F.CrtYd")
		)
		(fp_rect
			(start -0.8 -0.4)
			(end 0.8 0.4)
			(stroke
				(width 0.15)
				(type solid)
			)
			(fill no)
			(layer "F.Fab")
		)
		(pad "1" smd roundrect
			(at -0.7 0 270)
			(size 0.6 0.8)
			(layers "F.Cu" "F.Mask" "F.Paste")
			(roundrect_rratio 0.2)
			(net 38 "VDC")
			(pintype "passive")
		)
		(pad "2" smd roundrect
			(at 0.7 0 270)
			(size 0.6 0.8)
			(layers "F.Cu" "F.Mask" "F.Paste")
			(roundrect_rratio 0.2)
			(net 1 "GND")
			(pintype "passive")
		)
	)
	(footprint "antmicro-footprints:USON-10_2.5x1mm_P0.5mm"
		(layer "F.Cu")
		(at 84.8 168.5)
		(descr "USON-10 2.5x1mm_ Pitch 0.5mm")
		(tags "USON-10 2.5x1mm Pitch 0.5mm")
		(property "Reference" "U14"
			(at 0.018 -1.7 0)
			(layer "F.SilkS")
			(hide yes)
			(effects
				(font
					(size 0.7 0.7)
					(thickness 0.15)
				)
				(justify left bottom)
			)
		)
		(property "Value" "TPD4E05U06QDQARQ1"
			(at 0.018 2.499 0)
			(layer "F.Fab")
			(effects
				(font
					(size 0.7 0.7)
					(thickness 0.15)
				)
				(justify left bottom)
			)
		)
		(property "Datasheet" "https://www.ti.com/lit/ds/symlink/tpd4e05u06-q1.pdf?HQS=dis-mous-null-mousermode-dsf-pf-null-wwe&ts=1663591265741&ref_url=https%253A%252F%252Fwww.mouser.com%252F"
			(at 0 0 0)
			(layer "F.Fab")
			(hide yes)
			(effects
				(font
					(size 1.27 1.27)
					(thickness 0.15)
				)
			)
		)
		(property "Author" "Antmicro"
			(at 0 0 0)
			(layer "F.Fab")
			(hide yes)
			(effects
				(font
					(size 1 1)
					(thickness 0.15)
				)
			)
		)
		(property "License" "Apache-2.0"
			(at 0 0 0)
			(layer "F.Fab")
			(hide yes)
			(effects
				(font
					(size 1 1)
					(thickness 0.15)
				)
			)
		)
		(property "MPN" "TPD4E05U06QDQARQ1"
			(at 0 0 0)
			(layer "F.Fab")
			(hide yes)
			(effects
				(font
					(size 1 1)
					(thickness 0.15)
				)
			)
		)
		(property "Manufacturer" "Texas Instruments"
			(at 0 0 0)
			(layer "F.Fab")
			(hide yes)
			(effects
				(font
					(size 1 1)
					(thickness 0.15)
				)
			)
		)
		(sheetname "/HDMI + SD Card/")
		(sheetfile "hdmi-sd-card.kicad_sch")
		(attr smd)
		(fp_line
			(start 0.498 -1.401)
			(end -0.5 -1.401)
			(stroke
				(width 0.15)
				(type solid)
			)
			(layer "F.SilkS")
		)
		(fp_line
			(start 0.498 1.398)
			(end -0.5 1.398)
			(stroke
				(width 0.15)
				(type solid)
			)
			(layer "F.SilkS")
		)
		(fp_circle
			(center -0.68 -1.27)
			(end -0.63 -1.27)
			(stroke
				(width 0.15)
				(type solid)
			)
			(fill yes)
			(layer "F.SilkS")
		)
		(fp_rect
			(start -0.8 -1.5)
			(end 0.8 1.499)
			(stroke
				(width 0.05)
				(type solid)
			)
			(fill no)
			(layer "F.CrtYd")
		)
		(fp_line
			(start -0.5 -1)
			(end -0.5 1.249)
			(stroke
				(width 0.15)
				(type solid)
			)
			(layer "F.Fab")
		)
		(fp_line
			(start -0.5 1.249)
			(end 0.498 1.249)
			(stroke
				(width 0.15)
				(type solid)
			)
			(layer "F.Fab")
		)
		(fp_line
			(start -0.25 -1.25)
			(end -0.5 -1)
			(stroke
				(width 0.15)
				(type solid)
			)
			(layer "F.Fab")
		)
		(fp_line
			(start 0.498 -1.25)
			(end -0.25 -1.25)
			(stroke
				(width 0.15)
				(type solid)
			)
			(layer "F.Fab")
		)
		(fp_line
			(start 0.498 -1.25)
			(end 0.498 1.249)
			(stroke
				(width 0.15)
				(type solid)
			)
			(layer "F.Fab")
		)
		(pad "1" smd roundrect
			(at -0.387 -1 270)
			(size 0.25 0.55)
			(layers "F.Cu" "F.Mask" "F.Paste")
			(roundrect_rratio 0.25)
			(net 669 "/FPGA bank 16/SD.CD")
			(pintype "passive")
		)
		(pad "2" smd roundrect
			(at -0.387 -0.5 270)
			(size 0.25 0.55)
			(layers "F.Cu" "F.Mask" "F.Paste")
			(roundrect_rratio 0.25)
			(net 594 "/FPGA bank 16/SD.DAT1")
			(pintype "passive")
		)
		(pad "3" smd roundrect
			(at -0.387 0 270)
			(size 0.4 0.55)
			(layers "F.Cu" "F.Mask" "F.Paste")
			(roundrect_rratio 0.25)
			(net 1 "GND")
			(pintype "power_in")
		)
		(pad "4" smd roundrect
			(at -0.387 0.498 270)
			(size 0.25 0.55)
			(layers "F.Cu" "F.Mask" "F.Paste")
			(roundrect_rratio 0.25)
			(net 374 "/FPGA bank 16/SD.DAT0")
			(pintype "passive")
		)
		(pad "5" smd roundrect
			(at -0.387 0.998 270)
			(size 0.25 0.55)
			(layers "F.Cu" "F.Mask" "F.Paste")
			(roundrect_rratio 0.25)
			(net 756 "unconnected-(U14-Pad5)_1")
			(pintype "passive+no_connect")
		)
		(pad "6" smd roundrect
			(at 0.385 0.998 270)
			(size 0.25 0.55)
			(layers "F.Cu" "F.Mask" "F.Paste")
			(roundrect_rratio 0.25)
			(net 582 "unconnected-(U14-Pad5)")
			(pintype "passive+no_connect")
		)
		(pad "7" smd roundrect
			(at 0.385 0.498 270)
			(size 0.25 0.55)
			(layers "F.Cu" "F.Mask" "F.Paste")
			(roundrect_rratio 0.25)
			(net 374 "/FPGA bank 16/SD.DAT0")
			(pintype "passive")
		)
		(pad "8" smd roundrect
			(at 0.385 0 270)
			(size 0.4 0.55)
			(layers "F.Cu" "F.Mask" "F.Paste")
			(roundrect_rratio 0.25)
			(net 1 "GND")
			(pintype "passive")
		)
		(pad "9" smd roundrect
			(at 0.385 -0.5 270)
			(size 0.25 0.55)
			(layers "F.Cu" "F.Mask" "F.Paste")
			(roundrect_rratio 0.25)
			(net 594 "/FPGA bank 16/SD.DAT1")
			(pintype "passive")
		)
		(pad "10" smd roundrect
			(at 0.385 -1 270)
			(size 0.25 0.55)
			(layers "F.Cu" "F.Mask" "F.Paste")
			(roundrect_rratio 0.25)
			(net 669 "/FPGA bank 16/SD.CD")
			(pintype "passive")
		)
	)
	(footprint "antmicro-footprints:F_1206_3216Metric"
		(layer "F.Cu")
		(at 115.5 203.8 90)
		(property "Reference" "F2"
			(at 2.15 1.1 90)
			(layer "F.SilkS")
			(effects
				(font
					(size 0.7 0.7)
					(thickness 0.15)
				)
				(justify left bottom)
			)
		)
		(property "Value" "F_4A_1206"
			(at 0 2 90)
			(layer "F.Fab")
			(effects
				(font
					(size 0.7 0.7)
					(thickness 0.15)
				)
				(justify left bottom)
			)
		)
		(property "Datasheet" "https://www.littelfuse.com/media?resourcetype=datasheets&itemid=dbe9bcd7-6072-4adf-bf5b-d33e52a6b90f&filename=littelfuse-fuse-466-datasheet"
			(at 0 0 90)
			(layer "F.Fab")
			(hide yes)
			(effects
				(font
					(size 1.27 1.27)
					(thickness 0.15)
				)
			)
		)
		(property "Author" "Antmicro"
			(at 319.3 88.3 0)
			(layer "F.Fab")
			(hide yes)
			(effects
				(font
					(size 1 1)
					(thickness 0.15)
				)
			)
		)
		(property "License" "Apache-2.0"
			(at 319.3 88.3 0)
			(layer "F.Fab")
			(hide yes)
			(effects
				(font
					(size 1 1)
					(thickness 0.15)
				)
			)
		)
		(property "MPN" "0466004.NR "
			(at 319.3 88.3 0)
			(layer "F.Fab")
			(hide yes)
			(effects
				(font
					(size 1 1)
					(thickness 0.15)
				)
			)
		)
		(property "Manufacturer" "Littelfuse"
			(at 319.3 88.3 0)
			(layer "F.Fab")
			(hide yes)
			(effects
				(font
					(size 1 1)
					(thickness 0.15)
				)
			)
		)
		(sheetname "/Supply/")
		(sheetfile "supply.kicad_sch")
		(attr smd)
		(fp_line
			(start -0.413 -0.861)
			(end 0.36 -0.861)
			(stroke
				(width 0.15)
				(type solid)
			)
			(layer "F.SilkS")
		)
		(fp_line
			(start -0.413 0.792)
			(end 0.36 0.792)
			(stroke
				(width 0.15)
				(type solid)
			)
			(layer "F.SilkS")
		)
		(fp_rect
			(start -1.95 -1)
			(end 1.95 1)
			(stroke
				(width 0.05)
				(type solid)
			)
			(fill no)
			(layer "F.CrtYd")
		)
		(fp_line
			(start 1.624 -0.861)
			(end 1.624 0.792)
			(stroke
				(width 0.15)
				(type solid)
			)
			(layer "F.Fab")
		)
		(fp_line
			(start -1.677 -0.861)
			(end 1.624 -0.861)
			(stroke
				(width 0.15)
				(type solid)
			)
			(layer "F.Fab")
		)
		(fp_line
			(start 1.624 0.792)
			(end -1.677 0.792)
			(stroke
				(width 0.15)
				(type solid)
			)
			(layer "F.Fab")
		)
		(fp_line
			(start -1.677 0.792)
			(end -1.677 -0.861)
			(stroke
				(width 0.15)
				(type solid)
			)
			(layer "F.Fab")
		)
		(pad "1" smd rect
			(at -1.35 0 90)
			(size 1.143 2.032)
			(layers "F.Cu" "F.Mask" "F.Paste")
			(net 11 "+12V")
			(pintype "passive")
		)
		(pad "2" smd rect
			(at 1.35 0 90)
			(size 1.143 2.032)
			(layers "F.Cu" "F.Mask" "F.Paste")
			(net 596 "/Supply/12V_PCIE_fused")
			(pintype "passive")
		)
	)
)
